(kicad_pcb
	(version 20241229)
	(generator "pcbnew")
	(generator_version "9.0")
	(general
		(thickness 1.599998)
		(legacy_teardrops no)
	)
	(paper "A4")
	(title_block
		(title "Artix - Datacenter Secure Control Module (DC-SCM)")
		(date "2024-11-06")
		(rev "1.1.3")
		(comment 9 "footprints 453-457 of 544")
	)
	(layers
		(0 "F.Cu" signal)
		(4 "In1.Cu" signal)
		(6 "In2.Cu" signal)
		(8 "In3.Cu" signal)
		(10 "In4.Cu" signal)
		(12 "In5.Cu" signal)
		(14 "In6.Cu" signal)
		(2 "B.Cu" signal)
		(9 "F.Adhes" user "F.Adhesive")
		(11 "B.Adhes" user "B.Adhesive")
		(13 "F.Paste" user)
		(15 "B.Paste" user)
		(5 "F.SilkS" user "F.Silkscreen")
		(7 "B.SilkS" user "B.Silkscreen")
		(1 "F.Mask" user)
		(3 "B.Mask" user)
		(17 "Dwgs.User" user "User.Drawings")
		(19 "Cmts.User" user "User.Comments")
		(21 "Eco1.User" user "User.Eco1")
		(23 "Eco2.User" user "User.Eco2")
		(25 "Edge.Cuts" user)
		(27 "Margin" user)
		(31 "F.CrtYd" user "F.Courtyard")
		(29 "B.CrtYd" user "B.Courtyard")
		(35 "F.Fab" user)
		(33 "B.Fab" user)
	)
	(footprint "antmicro-footprints:C_0402_1005Metric"
		(layer "B.Cu")
		(at 141.774 127.514 -90)
		(descr "Capacitor SMD 0402")
		(tags "capacitor SMD 0402")
		(property "Reference" "C231"
			(at 1.086 2.974 90)
			(layer "B.SilkS")
			(effects
				(font
					(size 0.7 0.7)
					(thickness 0.15)
				)
				(justify left bottom mirror)
			)
		)
		(property "Value" "C_100n_6V3_0402"
			(at 0 -1.4 90)
			(layer "B.Fab")
			(effects
				(font
					(size 0.7 0.7)
					(thickness 0.15)
				)
				(justify left bottom mirror)
			)
		)
		(property "Datasheet" "https://www.passivecomponent.com/wp-content/uploads/datasheet/WTC_MLCC_General_Purpose.pdf"
			(at 0 0 270)
			(layer "F.Fab")
			(hide yes)
			(effects
				(font
					(size 1.27 1.27)
					(thickness 0.15)
				)
			)
		)
		(property "Description" "SMT Multilayer Ceramic Capacitor, 0.1 µF, 6.3 V, 0402 [1005 Metric], ± 10%, X5R, Walsin MLCC"
			(at 0 0 270)
			(layer "F.Fab")
			(hide yes)
			(effects
				(font
					(size 1.27 1.27)
					(thickness 0.15)
				)
			)
		)
		(property "Author" "Antmicro"
			(at 14.26 269.288 0)
			(layer "B.Fab")
			(hide yes)
			(effects
				(font
					(size 1 1)
					(thickness 0.15)
				)
				(justify mirror)
			)
		)
		(property "Dielectric" ""
			(at 14.26 269.288 0)
			(layer "B.Fab")
			(hide yes)
			(effects
				(font
					(size 1 1)
					(thickness 0.15)
				)
				(justify mirror)
			)
		)
		(property "License" "Apache-2.0"
			(at 14.26 269.288 0)
			(layer "B.Fab")
			(hide yes)
			(effects
				(font
					(size 1 1)
					(thickness 0.15)
				)
				(justify mirror)
			)
		)
		(property "MPN" "0402X104K6R3CT"
			(at 14.26 269.288 0)
			(layer "B.Fab")
			(hide yes)
			(effects
				(font
					(size 1 1)
					(thickness 0.15)
				)
				(justify mirror)
			)
		)
		(property "Manufacturer" "Walsin"
			(at 14.26 269.288 0)
			(layer "B.Fab")
			(hide yes)
			(effects
				(font
					(size 1 1)
					(thickness 0.15)
				)
				(justify mirror)
			)
		)
		(property "Public" "False"
			(at 14.26 269.288 0)
			(layer "B.Fab")
			(hide yes)
			(effects
				(font
					(size 1 1)
					(thickness 0.15)
				)
				(justify mirror)
			)
		)
		(property "Val" "100n"
			(at 14.26 269.288 0)
			(layer "B.Fab")
			(hide yes)
			(effects
				(font
					(size 1 1)
					(thickness 0.15)
				)
				(justify mirror)
			)
		)
		(property "Voltage" ""
			(at 14.26 269.288 0)
			(layer "B.Fab")
			(hide yes)
			(effects
				(font
					(size 1 1)
					(thickness 0.15)
				)
				(justify mirror)
			)
		)
		(sheetname "/Interfaces/")
		(sheetfile "interfaces.kicad_sch")
		(attr smd)
		(fp_rect
			(start -0.925 0.47)
			(end 0.925 -0.47)
			(stroke
				(width 0.05)
				(type default)
			)
			(fill no)
			(layer "B.CrtYd")
		)
		(fp_line
			(start -0.494 0.25)
			(end 0.504 0.25)
			(stroke
				(width 0.15)
				(type solid)
			)
			(layer "B.Fab")
		)
		(fp_line
			(start 0.504 0.25)
			(end 0.504 -0.248)
			(stroke
				(width 0.15)
				(type solid)
			)
			(layer "B.Fab")
		)
		(fp_line
			(start -0.494 -0.248)
			(end -0.494 0.25)
			(stroke
				(width 0.15)
				(type solid)
			)
			(layer "B.Fab")
		)
		(fp_line
			(start 0.504 -0.248)
			(end -0.494 -0.248)
			(stroke
				(width 0.15)
				(type solid)
			)
			(layer "B.Fab")
		)
		(pad "1" smd roundrect
			(at -0.48 0 270)
			(size 0.59 0.64)
			(layers "B.Cu" "B.Mask" "B.Paste")
			(roundrect_rratio 0.25)
			(net 1 "GND")
			(pintype "passive")
		)
		(pad "2" smd roundrect
			(at 0.48 0 270)
			(size 0.59 0.64)
			(layers "B.Cu" "B.Mask" "B.Paste")
			(roundrect_rratio 0.25)
			(net 2 "VCC3V3")
			(pintype "passive")
		)
	)
	(footprint "antmicro-footprints:C_0402_1005Metric"
		(layer "B.Cu")
		(at 140.774 127.514 -90)
		(descr "Capacitor SMD 0402")
		(tags "capacitor SMD 0402")
		(property "Reference" "C232"
			(at 1.086 2.974 90)
			(layer "B.SilkS")
			(effects
				(font
					(size 0.7 0.7)
					(thickness 0.15)
				)
				(justify left bottom mirror)
			)
		)
		(property "Value" "C_100n_6V3_0402"
			(at 0 -1.4 90)
			(layer "B.Fab")
			(effects
				(font
					(size 0.7 0.7)
					(thickness 0.15)
				)
				(justify left bottom mirror)
			)
		)
		(property "Datasheet" "https://www.passivecomponent.com/wp-content/uploads/datasheet/WTC_MLCC_General_Purpose.pdf"
			(at 0 0 270)
			(layer "F.Fab")
			(hide yes)
			(effects
				(font
					(size 1.27 1.27)
					(thickness 0.15)
				)
			)
		)
		(property "Description" "SMT Multilayer Ceramic Capacitor, 0.1 µF, 6.3 V, 0402 [1005 Metric], ± 10%, X5R, Walsin MLCC"
			(at 0 0 270)
			(layer "F.Fab")
			(hide yes)
			(effects
				(font
					(size 1.27 1.27)
					(thickness 0.15)
				)
			)
		)
		(property "Author" "Antmicro"
			(at 13.26 268.288 0)
			(layer "B.Fab")
			(hide yes)
			(effects
				(font
					(size 1 1)
					(thickness 0.15)
				)
				(justify mirror)
			)
		)
		(property "Dielectric" ""
			(at 13.26 268.288 0)
			(layer "B.Fab")
			(hide yes)
			(effects
				(font
					(size 1 1)
					(thickness 0.15)
				)
				(justify mirror)
			)
		)
		(property "License" "Apache-2.0"
			(at 13.26 268.288 0)
			(layer "B.Fab")
			(hide yes)
			(effects
				(font
					(size 1 1)
					(thickness 0.15)
				)
				(justify mirror)
			)
		)
		(property "MPN" "0402X104K6R3CT"
			(at 13.26 268.288 0)
			(layer "B.Fab")
			(hide yes)
			(effects
				(font
					(size 1 1)
					(thickness 0.15)
				)
				(justify mirror)
			)
		)
		(property "Manufacturer" "Walsin"
			(at 13.26 268.288 0)
			(layer "B.Fab")
			(hide yes)
			(effects
				(font
					(size 1 1)
					(thickness 0.15)
				)
				(justify mirror)
			)
		)
		(property "Public" "False"
			(at 13.26 268.288 0)
			(layer "B.Fab")
			(hide yes)
			(effects
				(font
					(size 1 1)
					(thickness 0.15)
				)
				(justify mirror)
			)
		)
		(property "Val" "100n"
			(at 13.26 268.288 0)
			(layer "B.Fab")
			(hide yes)
			(effects
				(font
					(size 1 1)
					(thickness 0.15)
				)
				(justify mirror)
			)
		)
		(property "Voltage" ""
			(at 13.26 268.288 0)
			(layer "B.Fab")
			(hide yes)
			(effects
				(font
					(size 1 1)
					(thickness 0.15)
				)
				(justify mirror)
			)
		)
		(sheetname "/Interfaces/")
		(sheetfile "interfaces.kicad_sch")
		(attr smd)
		(fp_rect
			(start -0.925 0.47)
			(end 0.925 -0.47)
			(stroke
				(width 0.05)
				(type default)
			)
			(fill no)
			(layer "B.CrtYd")
		)
		(fp_line
			(start -0.494 0.25)
			(end 0.504 0.25)
			(stroke
				(width 0.15)
				(type solid)
			)
			(layer "B.Fab")
		)
		(fp_line
			(start 0.504 0.25)
			(end 0.504 -0.248)
			(stroke
				(width 0.15)
				(type solid)
			)
			(layer "B.Fab")
		)
		(fp_line
			(start -0.494 -0.248)
			(end -0.494 0.25)
			(stroke
				(width 0.15)
				(type solid)
			)
			(layer "B.Fab")
		)
		(fp_line
			(start 0.504 -0.248)
			(end -0.494 -0.248)
			(stroke
				(width 0.15)
				(type solid)
			)
			(layer "B.Fab")
		)
		(pad "1" smd roundrect
			(at -0.48 0 270)
			(size 0.59 0.64)
			(layers "B.Cu" "B.Mask" "B.Paste")
			(roundrect_rratio 0.25)
			(net 1 "GND")
			(pintype "passive")
		)
		(pad "2" smd roundrect
			(at 0.48 0 270)
			(size 0.59 0.64)
			(layers "B.Cu" "B.Mask" "B.Paste")
			(roundrect_rratio 0.25)
			(net 2 "VCC3V3")
			(pintype "passive")
		)
	)
	(footprint "antmicro-footprints:R_0402_1005Metric"
		(layer "B.Cu")
		(at 77.975 148.175 180)
		(descr "Resistor SMD 0402")
		(tags "resistor SMD 0402")
		(property "Reference" "R161"
			(at 0.775 -0.425 0)
			(layer "B.SilkS")
			(effects
				(font
					(size 0.7 0.7)
					(thickness 0.15)
				)
				(justify left bottom mirror)
			)
		)
		(property "Value" "R_0R_0402"
			(at 0 -1.4 0)
			(layer "B.Fab")
			(effects
				(font
					(size 0.7 0.7)
					(thickness 0.15)
				)
				(justify left bottom mirror)
			)
		)
		(property "Datasheet" "https://industrial.panasonic.com/cdbs/www-data/pdf/RDA0000/AOA0000C301.pdf"
			(at 0 0 180)
			(layer "F.Fab")
			(hide yes)
			(effects
				(font
					(size 1.27 1.27)
					(thickness 0.15)
				)
			)
		)
		(property "Description" "SMD Chip Resistor, Jumper, 0 ohm, 100 mW, 0402 [1005 Metric], Thick Film, General Purpose"
			(at 0 0 180)
			(layer "F.Fab")
			(hide yes)
			(effects
				(font
					(size 1.27 1.27)
					(thickness 0.15)
				)
			)
		)
		(property "Author" "Antmicro"
			(at 155.95 296.35 0)
			(layer "B.Fab")
			(hide yes)
			(effects
				(font
					(size 1 1)
					(thickness 0.15)
				)
				(justify mirror)
			)
		)
		(property "Current" "1A"
			(at 155.95 296.35 0)
			(layer "B.Fab")
			(hide yes)
			(effects
				(font
					(size 1 1)
					(thickness 0.15)
				)
				(justify mirror)
			)
		)
		(property "License" "Apache-2.0"
			(at 155.95 296.35 0)
			(layer "B.Fab")
			(hide yes)
			(effects
				(font
					(size 1 1)
					(thickness 0.15)
				)
				(justify mirror)
			)
		)
		(property "MPN" "ERJ2GE0R00X"
			(at 155.95 296.35 0)
			(layer "B.Fab")
			(hide yes)
			(effects
				(font
					(size 1 1)
					(thickness 0.15)
				)
				(justify mirror)
			)
		)
		(property "Manufacturer" "Panasonic"
			(at 155.95 296.35 0)
			(layer "B.Fab")
			(hide yes)
			(effects
				(font
					(size 1 1)
					(thickness 0.15)
				)
				(justify mirror)
			)
		)
		(property "Tolerance" "~"
			(at 155.95 296.35 0)
			(layer "B.Fab")
			(hide yes)
			(effects
				(font
					(size 1 1)
					(thickness 0.15)
				)
				(justify mirror)
			)
		)
		(property "Val" "0R"
			(at 155.95 296.35 0)
			(layer "B.Fab")
			(hide yes)
			(effects
				(font
					(size 1 1)
					(thickness 0.15)
				)
				(justify mirror)
			)
		)
		(property "DNP" ""
			(at 0 0 180)
			(unlocked yes)
			(layer "B.Fab")
			(hide yes)
			(effects
				(font
					(size 1 1)
					(thickness 0.15)
				)
				(justify mirror)
			)
		)
		(sheetname "/FPGA banks 13-16/")
		(sheetfile "fpga-banks-13-16.kicad_sch")
		(attr smd)
		(fp_rect
			(start -0.925 0.47)
			(end 0.925 -0.47)
			(stroke
				(width 0.05)
				(type default)
			)
			(fill no)
			(layer "B.CrtYd")
		)
		(fp_rect
			(start -0.5 0.25)
			(end 0.5 -0.25)
			(stroke
				(width 0.15)
				(type solid)
			)
			(fill no)
			(layer "B.Fab")
		)
		(pad "1" smd roundrect
			(at -0.48 0 180)
			(size 0.59 0.64)
			(layers "B.Cu" "B.Mask" "B.Paste")
			(roundrect_rratio 0.25)
			(net 344 "Net-(U14A-IO_L6P_T0_FCS_B_14)")
			(pintype "passive")
		)
		(pad "2" smd roundrect
			(at 0.48 0 180)
			(size 0.59 0.64)
			(layers "B.Cu" "B.Mask" "B.Paste")
			(roundrect_rratio 0.25)
			(net 350 "ROT_QSPI_CS_B")
			(pintype "passive")
		)
	)
	(footprint "antmicro-footprints:C_0402_1005Metric"
		(layer "B.Cu")
		(at 96.275 109.927 180)
		(descr "Capacitor SMD 0402")
		(tags "capacitor SMD 0402")
		(property "Reference" "C234"
			(at 1.01 0.727 0)
			(layer "B.SilkS")
			(effects
				(font
					(size 0.7 0.7)
					(thickness 0.15)
				)
				(justify left bottom mirror)
			)
		)
		(property "Value" "C_470n_0402"
			(at 0 -1.4 0)
			(layer "B.Fab")
			(effects
				(font
					(size 0.7 0.7)
					(thickness 0.15)
				)
				(justify left bottom mirror)
			)
		)
		(property "Datasheet" "https://product.tdk.com/en/search/capacitor/ceramic/mlcc/info?part_no=C1005X5R1E474M050BB"
			(at 0 0 180)
			(layer "F.Fab")
			(hide yes)
			(effects
				(font
					(size 1.27 1.27)
					(thickness 0.15)
				)
			)
		)
		(property "Description" "SMD Multilayer Ceramic Capacitor, 0.47 µF, 25 V, 0402 [1005 Metric], ± 20%, X5R, C"
			(at 0 0 180)
			(layer "F.Fab")
			(hide yes)
			(effects
				(font
					(size 1.27 1.27)
					(thickness 0.15)
				)
			)
		)
		(property "Author" "Antmicro"
			(at 192.55 219.854 0)
			(layer "B.Fab")
			(hide yes)
			(effects
				(font
					(size 1 1)
					(thickness 0.15)
				)
				(justify mirror)
			)
		)
		(property "Dielectric" ""
			(at 192.55 219.854 0)
			(layer "B.Fab")
			(hide yes)
			(effects
				(font
					(size 1 1)
					(thickness 0.15)
				)
				(justify mirror)
			)
		)
		(property "License" "Apache-2.0"
			(at 192.55 219.854 0)
			(layer "B.Fab")
			(hide yes)
			(effects
				(font
					(size 1 1)
					(thickness 0.15)
				)
				(justify mirror)
			)
		)
		(property "MPN" "C1005X5R1E474M050BB"
			(at 192.55 219.854 0)
			(layer "B.Fab")
			(hide yes)
			(effects
				(font
					(size 1 1)
					(thickness 0.15)
				)
				(justify mirror)
			)
		)
		(property "Manufacturer" "TDK"
			(at 192.55 219.854 0)
			(layer "B.Fab")
			(hide yes)
			(effects
				(font
					(size 1 1)
					(thickness 0.15)
				)
				(justify mirror)
			)
		)
		(property "Val" "470n"
			(at 192.55 219.854 0)
			(layer "B.Fab")
			(hide yes)
			(effects
				(font
					(size 1 1)
					(thickness 0.15)
				)
				(justify mirror)
			)
		)
		(property "Voltage" ""
			(at 192.55 219.854 0)
			(layer "B.Fab")
			(hide yes)
			(effects
				(font
					(size 1 1)
					(thickness 0.15)
				)
				(justify mirror)
			)
		)
		(sheetname "/FPGA banks 13-16/")
		(sheetfile "fpga-banks-13-16.kicad_sch")
		(attr smd)
		(fp_rect
			(start -0.925 0.47)
			(end 0.925 -0.47)
			(stroke
				(width 0.05)
				(type default)
			)
			(fill no)
			(layer "B.CrtYd")
		)
		(fp_line
			(start 0.504 0.25)
			(end 0.504 -0.248)
			(stroke
				(width 0.15)
				(type solid)
			)
			(layer "B.Fab")
		)
		(fp_line
			(start 0.504 -0.248)
			(end -0.494 -0.248)
			(stroke
				(width 0.15)
				(type solid)
			)
			(layer "B.Fab")
		)
		(fp_line
			(start -0.494 0.25)
			(end 0.504 0.25)
			(stroke
				(width 0.15)
				(type solid)
			)
			(layer "B.Fab")
		)
		(fp_line
			(start -0.494 -0.248)
			(end -0.494 0.25)
			(stroke
				(width 0.15)
				(type solid)
			)
			(layer "B.Fab")
		)
		(pad "1" smd roundrect
			(at -0.48 0 180)
			(size 0.59 0.64)
			(layers "B.Cu" "B.Mask" "B.Paste")
			(roundrect_rratio 0.25)
			(net 1 "GND")
			(pintype "passive")
		)
		(pad "2" smd roundrect
			(at 0.48 0 180)
			(size 0.59 0.64)
			(layers "B.Cu" "B.Mask" "B.Paste")
			(roundrect_rratio 0.25)
			(net 2 "VCC3V3")
			(pintype "passive")
		)
	)
	(footprint "antmicro-footprints:C_0402_1005Metric"
		(layer "B.Cu")
		(at 64.555 126.995 90)
		(descr "Capacitor SMD 0402")
		(tags "capacitor SMD 0402")
		(property "Reference" "C36"
			(at -1.095 -0.575 90)
			(layer "B.SilkS")
			(effects
				(font
					(size 0.7 0.7)
					(thickness 0.15)
				)
				(justify right bottom mirror)
			)
		)
		(property "Value" "C_470n_0402"
			(at 0 -1.4 90)
			(layer "B.Fab")
			(effects
				(font
					(size 0.7 0.7)
					(thickness 0.15)
				)
				(justify right bottom mirror)
			)
		)
		(property "Datasheet" "https://product.tdk.com/en/search/capacitor/ceramic/mlcc/info?part_no=C1005X5R1E474M050BB"
			(at 0 0 90)
			(layer "F.Fab")
			(hide yes)
			(effects
				(font
					(size 1.27 1.27)
					(thickness 0.15)
				)
			)
		)
		(property "Description" "SMD Multilayer Ceramic Capacitor, 0.47 µF, 25 V, 0402 [1005 Metric], ± 20%, X5R, C"
			(at 0 0 90)
			(layer "F.Fab")
			(hide yes)
			(effects
				(font
					(size 1.27 1.27)
					(thickness 0.15)
				)
			)
		)
		(property "Author" "Antmicro"
			(at 191.55 62.44 0)
			(layer "B.Fab")
			(hide yes)
			(effects
				(font
					(size 1 1)
					(thickness 0.15)
				)
				(justify mirror)
			)
		)
		(property "Dielectric" ""
			(at 191.55 62.44 0)
			(layer "B.Fab")
			(hide yes)
			(effects
				(font
					(size 1 1)
					(thickness 0.15)
				)
				(justify mirror)
			)
		)
		(property "License" "Apache-2.0"
			(at 191.55 62.44 0)
			(layer "B.Fab")
			(hide yes)
			(effects
				(font
					(size 1 1)
					(thickness 0.15)
				)
				(justify mirror)
			)
		)
		(property "MPN" "C1005X5R1E474M050BB"
			(at 191.55 62.44 0)
			(layer "B.Fab")
			(hide yes)
			(effects
				(font
					(size 1 1)
					(thickness 0.15)
				)
				(justify mirror)
			)
		)
		(property "Manufacturer" "TDK"
			(at 191.55 62.44 0)
			(layer "B.Fab")
			(hide yes)
			(effects
				(font
					(size 1 1)
					(thickness 0.15)
				)
				(justify mirror)
			)
		)
		(property "Val" "470n"
			(at 191.55 62.44 0)
			(layer "B.Fab")
			(hide yes)
			(effects
				(font
					(size 1 1)
					(thickness 0.15)
				)
				(justify mirror)
			)
		)
		(property "Voltage" ""
			(at 191.55 62.44 0)
			(layer "B.Fab")
			(hide yes)
			(effects
				(font
					(size 1 1)
					(thickness 0.15)
				)
				(justify mirror)
			)
		)
		(sheetname "/RoT/")
		(sheetfile "rot.kicad_sch")
		(attr smd)
		(fp_rect
			(start -0.925 0.47)
			(end 0.925 -0.47)
			(stroke
				(width 0.05)
				(type default)
			)
			(fill no)
			(layer "B.CrtYd")
		)
		(fp_line
			(start 0.504 -0.248)
			(end -0.494 -0.248)
			(stroke
				(width 0.15)
				(type solid)
			)
			(layer "B.Fab")
		)
		(fp_line
			(start -0.494 -0.248)
			(end -0.494 0.25)
			(stroke
				(width 0.15)
				(type solid)
			)
			(layer "B.Fab")
		)
		(fp_line
			(start 0.504 0.25)
			(end 0.504 -0.248)
			(stroke
				(width 0.15)
				(type solid)
			)
			(layer "B.Fab")
		)
		(fp_line
			(start -0.494 0.25)
			(end 0.504 0.25)
			(stroke
				(width 0.15)
				(type solid)
			)
			(layer "B.Fab")
		)
		(pad "1" smd roundrect
			(at -0.48 0 90)
			(size 0.59 0.64)
			(layers "B.Cu" "B.Mask" "B.Paste")
			(roundrect_rratio 0.25)
			(net 1 "GND")
			(pintype "passive")
		)
		(pad "2" smd roundrect
			(at 0.48 0 90)
			(size 0.59 0.64)
			(layers "B.Cu" "B.Mask" "B.Paste")
			(roundrect_rratio 0.25)
			(net 2 "VCC3V3")
			(pintype "passive")
		)
	)
)
